(kicad_pcb
	(version 20260206)
	(generator "pcbnew")
	(generator_version "10.0")
	(general
		(thickness 1.6)
		(legacy_teardrops no)
	)
	(paper "A4")
	(title_block
		(title "timecard-production-celestica-r4006 — R4006-B0001-02_R01.brd")
		(comment 1 "Time Appliance Project (Time Card) / footprints 423-427 of 1113")
	)
	(layers
		(0 "F.Cu" signal "TOP")
		(4 "In1.Cu" signal "L02_GND1")
		(6 "In2.Cu" signal "L03_SIG1")
		(8 "In3.Cu" signal "L04_GND2")
		(10 "In4.Cu" signal "L05_VCC1")
		(12 "In5.Cu" signal "L06_VCC2")
		(14 "In6.Cu" signal "L07_GND3")
		(16 "In7.Cu" signal "L08_SIG2")
		(18 "In8.Cu" signal "L09_GND4")
		(2 "B.Cu" signal "BOTTOM")
		(9 "F.Adhes" user "F.Adhesive")
		(11 "B.Adhes" user "B.Adhesive")
		(13 "F.Paste" user "Package Geometry/Pastemask Top")
		(15 "B.Paste" user "Package Geometry/Pastemask Bottom")
		(5 "F.SilkS" user "Ref Des/Silkscreen Top")
		(7 "B.SilkS" user "Ref Des/Silkscreen Bottom")
		(1 "F.Mask" user "Board Geometry/Soldermask Top")
		(3 "B.Mask" user "Board Geometry/Soldermask Bottom")
		(17 "Dwgs.User" user "User.Drawings")
		(19 "Cmts.User" user "User.Comments")
		(21 "Eco1.User" user "User.Eco1")
		(23 "Eco2.User" user "User.Eco2")
		(25 "Edge.Cuts" user "Board Geometry/Outline")
		(27 "Margin" user)
		(31 "F.CrtYd" user "Package Geometry/Place Bound Top")
		(29 "B.CrtYd" user "Package Geometry/Place Bound Bottom")
		(35 "F.Fab" user "Ref Des/Assembly Top")
		(33 "B.Fab" user "Ref Des/Assembly Bottom")
	)
	(footprint ""
		(layer "F.Cu")
		(at 12.192 -52.578 90)
		(property "Reference" "R372"
			(at -0.508 -3.13563 90)
			(unlocked yes)
			(layer "F.SilkS")
			(effects
				(font
					(size 0.7874 0.5842)
					(thickness 0.1524)
				)
			)
		)
		(property "Value" "VAL*"
			(at 0.02032 2.13233 90)
			(unlocked yes)
			(layer "F.Fab")
			(hide yes)
			(effects
				(font
					(size 0.7874 0.5842)
					(thickness 0.1524)
				)
			)
		)
		(property "Tolerance" "TOL*"
			(at 0.044704 3.05435 90)
			(unlocked yes)
			(layer "Cmts.User")
			(hide yes)
			(effects
				(font
					(size 0.7874 0.5842)
					(thickness 0.1524)
				)
			)
		)
		(property "User Part Number" "PARTNUM*"
			(at 0.02032 4.024884 90)
			(unlocked yes)
			(layer "Cmts.User")
			(hide yes)
			(effects
				(font
					(size 0.7874 0.5842)
					(thickness 0.1524)
				)
			)
		)
		(property "Device Type" "RESISTOR-G155-149R9-01,49.9OHMA"
			(at 0.008382 1.210564 90)
			(unlocked yes)
			(layer "F.Fab")
			(hide yes)
			(effects
				(font
					(size 0.7874 0.5842)
					(thickness 0.1524)
				)
			)
		)
		(duplicate_pad_numbers_are_jumpers no)
		(fp_line
			(start 1.143 -0.5588)
			(end -1.143 -0.5588)
			(stroke
				(width 0.1)
				(type default)
			)
			(layer "F.SilkS")
		)
		(fp_line
			(start -1.143 -0.5588)
			(end -1.143 0.5588)
			(stroke
				(width 0.1)
				(type default)
			)
			(layer "F.SilkS")
		)
		(fp_line
			(start 1.143 0.5588)
			(end 1.143 -0.5588)
			(stroke
				(width 0.1)
				(type default)
			)
			(layer "F.SilkS")
		)
		(fp_line
			(start -1.143 0.5588)
			(end 1.143 0.5588)
			(stroke
				(width 0.1)
				(type default)
			)
			(layer "F.SilkS")
		)
		(fp_poly
			(pts
				(xy -1.143 0.5588) (xy 1.143 0.5588) (xy 1.143 -0.5588) (xy -1.143 -0.5588)
			)
			(stroke
				(width 0)
				(type default)
			)
			(fill no)
			(layer "F.CrtYd")
		)
		(fp_line
			(start 0.508 -0.3048)
			(end -0.508 -0.3048)
			(stroke
				(width 0.1)
				(type default)
			)
			(layer "F.Fab")
		)
		(fp_line
			(start -0.508 -0.3048)
			(end -0.508 0.3048)
			(stroke
				(width 0.1)
				(type default)
			)
			(layer "F.Fab")
		)
		(fp_line
			(start 0.508 0.3048)
			(end 0.508 -0.3048)
			(stroke
				(width 0.1)
				(type default)
			)
			(layer "F.Fab")
		)
		(fp_line
			(start -0.508 0.3048)
			(end 0.508 0.3048)
			(stroke
				(width 0.1)
				(type default)
			)
			(layer "F.Fab")
		)
		(pad "1" smd rect
			(at -0.5334 0 90)
			(size 0.7112 0.6096)
			(layers "F.Cu" "F.Mask" "F.Paste")
			(net "BF_ANT2_IN")
		)
		(pad "2" smd rect
			(at 0.5334 0 90)
			(size 0.7112 0.6096)
			(layers "F.Cu" "F.Mask" "F.Paste")
			(net "ANT2_IN")
		)
		(zone
			(layer "F.Cu")
			(hatch none 0.5)
			(connect_pads
				(clearance 0)
			)
			(min_thickness 0.25)
			(keepout
				(tracks allowed)
				(vias not_allowed)
				(pads allowed)
				(copperpour not_allowed)
				(footprints allowed)
			)
			(placement
				(enabled no)
				(sheetname "")
			)
			(fill
				(thermal_gap 0.5)
				(thermal_bridge_width 0.5)
				(island_removal_mode 0)
			)
			(polygon
				(pts
					(xy 12.4968 -52.5018) (xy 12.4968 -52.6542) (xy 11.8872 -52.6542) (xy 11.8872 -52.5018)
				)
			)
		)
		(zone
			(layer "F.Cu")
			(hatch none 0.5)
			(connect_pads
				(clearance 0)
			)
			(min_thickness 0.25)
			(keepout
				(tracks not_allowed)
				(vias allowed)
				(pads allowed)
				(copperpour not_allowed)
				(footprints allowed)
			)
			(placement
				(enabled no)
				(sheetname "")
			)
			(fill
				(thermal_gap 0.5)
				(thermal_bridge_width 0.5)
				(island_removal_mode 0)
			)
			(polygon
				(pts
					(xy 12.4968 -52.5018) (xy 12.4968 -52.6542) (xy 11.8872 -52.6542) (xy 11.8872 -52.5018)
				)
			)
		)
	)
	(footprint ""
		(layer "F.Cu")
		(at 141.097 -59.563 90)
		(property "Reference" "C256"
			(at 3.048 -1.73863 90)
			(unlocked yes)
			(layer "F.SilkS")
			(effects
				(font
					(size 0.7874 0.5842)
					(thickness 0.1524)
				)
			)
		)
		(property "Value" "VAL*"
			(at 0.0762 2.067306 90)
			(unlocked yes)
			(layer "F.Fab")
			(hide yes)
			(effects
				(font
					(size 0.7874 0.5842)
					(thickness 0.1524)
				)
			)
		)
		(property "Device Type" "CAPACITOR-G105-0B104-CK,0.1UF,A"
			(at 0.0508 1.127506 90)
			(unlocked yes)
			(layer "F.Fab")
			(hide yes)
			(effects
				(font
					(size 0.7874 0.5842)
					(thickness 0.1524)
				)
			)
		)
		(property "User Part Number" "PARTNUM*"
			(at 0.1016 4.023106 90)
			(unlocked yes)
			(layer "Cmts.User")
			(hide yes)
			(effects
				(font
					(size 0.7874 0.5842)
					(thickness 0.1524)
				)
			)
		)
		(property "Tolerance" "TOL*"
			(at 0.0762 3.032506 90)
			(unlocked yes)
			(layer "Cmts.User")
			(hide yes)
			(effects
				(font
					(size 0.7874 0.5842)
					(thickness 0.1524)
				)
			)
		)
		(duplicate_pad_numbers_are_jumpers no)
		(fp_line
			(start 1.143 -0.5588)
			(end -1.143 -0.5588)
			(stroke
				(width 0.1)
				(type default)
			)
			(layer "F.SilkS")
		)
		(fp_line
			(start -1.143 -0.5588)
			(end -1.143 0.5588)
			(stroke
				(width 0.1)
				(type default)
			)
			(layer "F.SilkS")
		)
		(fp_line
			(start 1.143 0.5588)
			(end 1.143 -0.5588)
			(stroke
				(width 0.1)
				(type default)
			)
			(layer "F.SilkS")
		)
		(fp_line
			(start -1.143 0.5588)
			(end 1.143 0.5588)
			(stroke
				(width 0.1)
				(type default)
			)
			(layer "F.SilkS")
		)
		(fp_rect
			(start -1.143 -0.5588)
			(end 1.143 0.5588)
			(stroke
				(width 0)
				(type default)
			)
			(fill no)
			(layer "F.CrtYd")
		)
		(fp_line
			(start 0.508 -0.3048)
			(end -0.508 -0.3048)
			(stroke
				(width 0.1)
				(type default)
			)
			(layer "F.Fab")
		)
		(fp_line
			(start -0.508 -0.3048)
			(end -0.508 0.3048)
			(stroke
				(width 0.1)
				(type default)
			)
			(layer "F.Fab")
		)
		(fp_line
			(start 0.508 0.3048)
			(end 0.508 -0.3048)
			(stroke
				(width 0.1)
				(type default)
			)
			(layer "F.Fab")
		)
		(fp_line
			(start -0.508 0.3048)
			(end 0.508 0.3048)
			(stroke
				(width 0.1)
				(type default)
			)
			(layer "F.Fab")
		)
		(pad "1" smd rect
			(at -0.5334 0 90)
			(size 0.7112 0.6096)
			(layers "F.Cu" "F.Mask" "F.Paste")
			(net "UNNAMED_523_CAPACITOR_I7_1")
		)
		(pad "2" smd rect
			(at 0.5334 0 90)
			(size 0.7112 0.6096)
			(layers "F.Cu" "F.Mask" "F.Paste")
			(net "SG")
		)
		(zone
			(layer "F.Cu")
			(hatch none 0.5)
			(connect_pads
				(clearance 0)
			)
			(min_thickness 0.25)
			(keepout
				(tracks allowed)
				(vias not_allowed)
				(pads allowed)
				(copperpour not_allowed)
				(footprints allowed)
			)
			(placement
				(enabled no)
				(sheetname "")
			)
			(fill
				(thermal_gap 0.5)
				(thermal_bridge_width 0.5)
				(island_removal_mode 0)
			)
			(polygon
				(pts
					(xy 140.7922 -59.4868) (xy 141.4018 -59.4868) (xy 141.4018 -59.6392) (xy 140.7922 -59.6392)
				)
			)
		)
	)
	(footprint ""
		(layer "F.Cu")
		(at 9.652 -81.534 90)
		(property "Reference" "R426"
			(at -2.667 -0.08763 90)
			(unlocked yes)
			(layer "F.SilkS")
			(effects
				(font
					(size 0.7874 0.5842)
					(thickness 0.1524)
				)
			)
		)
		(property "Value" "VAL*"
			(at 0.02032 2.13233 90)
			(unlocked yes)
			(layer "F.Fab")
			(hide yes)
			(effects
				(font
					(size 0.7874 0.5842)
					(thickness 0.1524)
				)
			)
		)
		(property "Device Type" "RESISTOR-G155-11000-01,100OHM,A"
			(at 0.008382 1.210564 90)
			(unlocked yes)
			(layer "F.Fab")
			(hide yes)
			(effects
				(font
					(size 0.7874 0.5842)
					(thickness 0.1524)
				)
			)
		)
		(property "User Part Number" "PARTNUM*"
			(at 0.02032 4.024884 90)
			(unlocked yes)
			(layer "Cmts.User")
			(hide yes)
			(effects
				(font
					(size 0.7874 0.5842)
					(thickness 0.1524)
				)
			)
		)
		(property "Tolerance" "TOL*"
			(at 0.044704 3.05435 90)
			(unlocked yes)
			(layer "Cmts.User")
			(hide yes)
			(effects
				(font
					(size 0.7874 0.5842)
					(thickness 0.1524)
				)
			)
		)
		(duplicate_pad_numbers_are_jumpers no)
		(fp_line
			(start 1.143 -0.5588)
			(end -1.143 -0.5588)
			(stroke
				(width 0.1)
				(type default)
			)
			(layer "F.SilkS")
		)
		(fp_line
			(start -1.143 -0.5588)
			(end -1.143 0.5588)
			(stroke
				(width 0.1)
				(type default)
			)
			(layer "F.SilkS")
		)
		(fp_line
			(start 1.143 0.5588)
			(end 1.143 -0.5588)
			(stroke
				(width 0.1)
				(type default)
			)
			(layer "F.SilkS")
		)
		(fp_line
			(start -1.143 0.5588)
			(end 1.143 0.5588)
			(stroke
				(width 0.1)
				(type default)
			)
			(layer "F.SilkS")
		)
		(fp_poly
			(pts
				(xy -1.143 0.5588) (xy 1.143 0.5588) (xy 1.143 -0.5588) (xy -1.143 -0.5588)
			)
			(stroke
				(width 0)
				(type default)
			)
			(fill no)
			(layer "F.CrtYd")
		)
		(fp_line
			(start 0.508 -0.3048)
			(end -0.508 -0.3048)
			(stroke
				(width 0.1)
				(type default)
			)
			(layer "F.Fab")
		)
		(fp_line
			(start -0.508 -0.3048)
			(end -0.508 0.3048)
			(stroke
				(width 0.1)
				(type default)
			)
			(layer "F.Fab")
		)
		(fp_line
			(start 0.508 0.3048)
			(end 0.508 -0.3048)
			(stroke
				(width 0.1)
				(type default)
			)
			(layer "F.Fab")
		)
		(fp_line
			(start -0.508 0.3048)
			(end 0.508 0.3048)
			(stroke
				(width 0.1)
				(type default)
			)
			(layer "F.Fab")
		)
		(pad "1" smd rect
			(at -0.5334 0 90)
			(size 0.7112 0.6096)
			(layers "F.Cu" "F.Mask" "F.Paste")
			(net "FPGA_OUT_GPS_LED_GREEN_N")
		)
		(pad "2" smd rect
			(at 0.5334 0 90)
			(size 0.7112 0.6096)
			(layers "F.Cu" "F.Mask" "F.Paste")
			(net "UNNAMED_14_LED4PV14_I269_4")
		)
		(zone
			(layer "F.Cu")
			(hatch none 0.5)
			(connect_pads
				(clearance 0)
			)
			(min_thickness 0.25)
			(keepout
				(tracks allowed)
				(vias not_allowed)
				(pads allowed)
				(copperpour not_allowed)
				(footprints allowed)
			)
			(placement
				(enabled no)
				(sheetname "")
			)
			(fill
				(thermal_gap 0.5)
				(thermal_bridge_width 0.5)
				(island_removal_mode 0)
			)
			(polygon
				(pts
					(xy 9.9568 -81.4578) (xy 9.9568 -81.6102) (xy 9.3472 -81.6102) (xy 9.3472 -81.4578)
				)
			)
		)
		(zone
			(layer "F.Cu")
			(hatch none 0.5)
			(connect_pads
				(clearance 0)
			)
			(min_thickness 0.25)
			(keepout
				(tracks not_allowed)
				(vias allowed)
				(pads allowed)
				(copperpour not_allowed)
				(footprints allowed)
			)
			(placement
				(enabled no)
				(sheetname "")
			)
			(fill
				(thermal_gap 0.5)
				(thermal_bridge_width 0.5)
				(island_removal_mode 0)
			)
			(polygon
				(pts
					(xy 9.9568 -81.4578) (xy 9.9568 -81.6102) (xy 9.3472 -81.6102) (xy 9.3472 -81.4578)
				)
			)
		)
	)
	(footprint ""
		(layer "F.Cu")
		(at 137.795 -17.526)
		(property "Reference" "R231"
			(at -1.397 1.56337 0)
			(unlocked yes)
			(layer "F.SilkS")
			(effects
				(font
					(size 0.7874 0.5842)
					(thickness 0.1524)
				)
			)
		)
		(property "Value" "VAL*"
			(at 0.0508 2.245106 0)
			(unlocked yes)
			(layer "F.Fab")
			(hide yes)
			(effects
				(font
					(size 0.7874 0.5842)
					(thickness 0.1524)
				)
			)
		)
		(property "Tolerance" "TOL*"
			(at 0.0508 3.261106 0)
			(unlocked yes)
			(layer "Cmts.User")
			(hide yes)
			(effects
				(font
					(size 0.7874 0.5842)
					(thickness 0.1524)
				)
			)
		)
		(property "Device Type" "RESISTOR-G155-04221-01,4.22KOHA"
			(at 0.0762 1.254506 0)
			(unlocked yes)
			(layer "F.Fab")
			(hide yes)
			(effects
				(font
					(size 0.7874 0.5842)
					(thickness 0.1524)
				)
			)
		)
		(property "User Part Number" "PARTNUM*"
			(at 0.0762 4.302506 0)
			(unlocked yes)
			(layer "Cmts.User")
			(hide yes)
			(effects
				(font
					(size 0.7874 0.5842)
					(thickness 0.1524)
				)
			)
		)
		(duplicate_pad_numbers_are_jumpers no)
		(fp_line
			(start -1.143 -0.5588)
			(end -1.143 0.5588)
			(stroke
				(width 0.1)
				(type default)
			)
			(layer "F.SilkS")
		)
		(fp_line
			(start -1.143 0.5588)
			(end 1.143 0.5588)
			(stroke
				(width 0.1)
				(type default)
			)
			(layer "F.SilkS")
		)
		(fp_line
			(start 1.143 -0.5588)
			(end -1.143 -0.5588)
			(stroke
				(width 0.1)
				(type default)
			)
			(layer "F.SilkS")
		)
		(fp_line
			(start 1.143 0.5588)
			(end 1.143 -0.5588)
			(stroke
				(width 0.1)
				(type default)
			)
			(layer "F.SilkS")
		)
		(fp_rect
			(start -1.143 -0.5588)
			(end 1.143 0.5588)
			(stroke
				(width 0)
				(type default)
			)
			(fill no)
			(layer "F.CrtYd")
		)
		(fp_line
			(start -0.508 -0.3048)
			(end -0.508 0.3048)
			(stroke
				(width 0.1)
				(type default)
			)
			(layer "F.Fab")
		)
		(fp_line
			(start -0.508 0.3048)
			(end 0.508 0.3048)
			(stroke
				(width 0.1)
				(type default)
			)
			(layer "F.Fab")
		)
		(fp_line
			(start 0.508 -0.3048)
			(end -0.508 -0.3048)
			(stroke
				(width 0.1)
				(type default)
			)
			(layer "F.Fab")
		)
		(fp_line
			(start 0.508 0.3048)
			(end 0.508 -0.3048)
			(stroke
				(width 0.1)
				(type default)
			)
			(layer "F.Fab")
		)
		(pad "1" smd rect
			(at -0.5334 0)
			(size 0.7112 0.6096)
			(layers "F.Cu" "F.Mask" "F.Paste")
			(net "XP2R5V_FPGA")
		)
		(pad "2" smd rect
			(at 0.5334 0)
			(size 0.7112 0.6096)
			(layers "F.Cu" "F.Mask" "F.Paste")
			(net "UNNAMED_515_ISL80101IRAJZDFN10_")
		)
		(zone
			(layer "F.Cu")
			(hatch none 0.5)
			(connect_pads
				(clearance 0)
			)
			(min_thickness 0.25)
			(keepout
				(tracks allowed)
				(vias not_allowed)
				(pads allowed)
				(copperpour not_allowed)
				(footprints allowed)
			)
			(placement
				(enabled no)
				(sheetname "")
			)
			(fill
				(thermal_gap 0.5)
				(thermal_bridge_width 0.5)
				(island_removal_mode 0)
			)
			(polygon
				(pts
					(xy 137.7188 -17.8308) (xy 137.7188 -17.2212) (xy 137.8712 -17.2212) (xy 137.8712 -17.8308)
				)
			)
		)
	)
	(footprint ""
		(layer "F.Cu")
		(at 119.761 -23.241)
		(property "Reference" "R486"
			(at -2.794 0.54737 0)
			(unlocked yes)
			(layer "F.SilkS")
			(effects
				(font
					(size 0.7874 0.5842)
					(thickness 0.1524)
				)
			)
		)
		(property "Value" "VAL*"
			(at 0.02032 2.13233 0)
			(unlocked yes)
			(layer "F.Fab")
			(hide yes)
			(effects
				(font
					(size 0.7874 0.5842)
					(thickness 0.1524)
				)
			)
		)
		(property "Tolerance" "TOL*"
			(at 0.044704 3.05435 0)
			(unlocked yes)
			(layer "Cmts.User")
			(hide yes)
			(effects
				(font
					(size 0.7874 0.5842)
					(thickness 0.1524)
				)
			)
		)
		(property "User Part Number" "PARTNUM*"
			(at 0.02032 4.024884 0)
			(unlocked yes)
			(layer "Cmts.User")
			(hide yes)
			(effects
				(font
					(size 0.7874 0.5842)
					(thickness 0.1524)
				)
			)
		)
		(property "Device Type" "RESISTOR-G155-133R0-01,33OHM,1%"
			(at 0.008382 1.210564 0)
			(unlocked yes)
			(layer "F.Fab")
			(hide yes)
			(effects
				(font
					(size 0.7874 0.5842)
					(thickness 0.1524)
				)
			)
		)
		(duplicate_pad_numbers_are_jumpers no)
		(fp_line
			(start -1.143 -0.5588)
			(end -1.143 0.5588)
			(stroke
				(width 0.1)
				(type default)
			)
			(layer "F.SilkS")
		)
		(fp_line
			(start -1.143 0.5588)
			(end 1.143 0.5588)
			(stroke
				(width 0.1)
				(type default)
			)
			(layer "F.SilkS")
		)
		(fp_line
			(start 1.143 -0.5588)
			(end -1.143 -0.5588)
			(stroke
				(width 0.1)
				(type default)
			)
			(layer "F.SilkS")
		)
		(fp_line
			(start 1.143 0.5588)
			(end 1.143 -0.5588)
			(stroke
				(width 0.1)
				(type default)
			)
			(layer "F.SilkS")
		)
		(fp_poly
			(pts
				(xy -1.143 0.5588) (xy 1.143 0.5588) (xy 1.143 -0.5588) (xy -1.143 -0.5588)
			)
			(stroke
				(width 0)
				(type default)
			)
			(fill no)
			(layer "F.CrtYd")
		)
		(fp_line
			(start -0.508 -0.3048)
			(end -0.508 0.3048)
			(stroke
				(width 0.1)
				(type default)
			)
			(layer "F.Fab")
		)
		(fp_line
			(start -0.508 0.3048)
			(end 0.508 0.3048)
			(stroke
				(width 0.1)
				(type default)
			)
			(layer "F.Fab")
		)
		(fp_line
			(start 0.508 -0.3048)
			(end -0.508 -0.3048)
			(stroke
				(width 0.1)
				(type default)
			)
			(layer "F.Fab")
		)
		(fp_line
			(start 0.508 0.3048)
			(end 0.508 -0.3048)
			(stroke
				(width 0.1)
				(type default)
			)
			(layer "F.Fab")
		)
		(pad "1" smd rect
			(at -0.5334 0)
			(size 0.7112 0.6096)
			(layers "F.Cu" "F.Mask" "F.Paste")
			(net "FT4232_MUX3_SEL")
		)
		(pad "2" smd rect
			(at 0.5334 0)
			(size 0.7112 0.6096)
			(layers "F.Cu" "F.Mask" "F.Paste")
			(net "MUX3_SEL")
		)
		(zone
			(layer "F.Cu")
			(hatch none 0.5)
			(connect_pads
				(clearance 0)
			)
			(min_thickness 0.25)
			(keepout
				(tracks allowed)
				(vias not_allowed)
				(pads allowed)
				(copperpour not_allowed)
				(footprints allowed)
			)
			(placement
				(enabled no)
				(sheetname "")
			)
			(fill
				(thermal_gap 0.5)
				(thermal_bridge_width 0.5)
				(island_removal_mode 0)
			)
			(polygon
				(pts
					(xy 119.6848 -22.9362) (xy 119.8372 -22.9362) (xy 119.8372 -23.5458) (xy 119.6848 -23.5458)
				)
			)
		)
		(zone
			(layer "F.Cu")
			(hatch none 0.5)
			(connect_pads
				(clearance 0)
			)
			(min_thickness 0.25)
			(keepout
				(tracks not_allowed)
				(vias allowed)
				(pads allowed)
				(copperpour not_allowed)
				(footprints allowed)
			)
			(placement
				(enabled no)
				(sheetname "")
			)
			(fill
				(thermal_gap 0.5)
				(thermal_bridge_width 0.5)
				(island_removal_mode 0)
			)
			(polygon
				(pts
					(xy 119.6848 -22.9362) (xy 119.8372 -22.9362) (xy 119.8372 -23.5458) (xy 119.6848 -23.5458)
				)
			)
		)
	)
)
